# BASEBOARD_FAB2 (Tioga Pass) — schematic netlist excerpt (pin names and nets, part order shuffled) for the footprints in the layout excerpt that follows; sources: Cadence DE-HDL packaged netlist, KiCad conversion of Wiwynn_Tioga_Pass_MB.brd

CT31  CAP_A  0.1UF 16V 10% X7R  pkg 0402V  page 224 : A = VR_PVDDQ_GHJ_AIREF2 ; B = GND
T1P27  TPAD-SE-2P-GP  pkg DISCRET-GA1  page 256 : \1\ = L5_40OHM_6INCH ; GND1 = GND
R25W143  RES  0.0 5% CHIP  pkg 0402  page 147 : A = FM_GLOBAL_RST_WARN_N_R ; B = FM_GLOBAL_RST_WARN_N

(kicad_pcb
	(version 20260206)
	(generator "pcbnew")
	(generator_version "10.0")
	(general
		(thickness 1.6)
		(legacy_teardrops no)
	)
	(paper "A4")
	(title_block
		(title "Wiwynn_Tioga_Pass_MB.brd")
		(comment 1 "Tioga Pass / footprints 1577-1579 of 4770")
	)
	(layers
		(0 "F.Cu" signal "TOP")
		(4 "In1.Cu" signal "L2GND")
		(6 "In2.Cu" signal "L3")
		(8 "In3.Cu" signal "L4GND")
		(10 "In4.Cu" signal "L5")
		(12 "In5.Cu" signal "L6GND")
		(14 "In6.Cu" signal "L7VCC")
		(16 "In7.Cu" signal "L8VCC")
		(18 "In8.Cu" signal "L9GND")
		(20 "In9.Cu" signal "L10")
		(22 "In10.Cu" signal "L11GND")
		(24 "In11.Cu" signal "L12")
		(26 "In12.Cu" signal "L13GND")
		(2 "B.Cu" signal "BOTTOM")
		(9 "F.Adhes" user "F.Adhesive")
		(11 "B.Adhes" user "B.Adhesive")
		(13 "F.Paste" user "Package Geometry/Pastemask Top")
		(15 "B.Paste" user "Package Geometry/Pastemask Bottom")
		(5 "F.SilkS" user "Ref Des/Silkscreen Top")
		(7 "B.SilkS" user "Ref Des/Silkscreen Bottom")
		(1 "F.Mask" user "Board Geometry/Soldermask Top")
		(3 "B.Mask" user "Board Geometry/Soldermask Bottom")
		(17 "Dwgs.User" user "User.Drawings")
		(19 "Cmts.User" user "User.Comments")
		(21 "Eco1.User" user "User.Eco1")
		(23 "Eco2.User" user "User.Eco2")
		(25 "Edge.Cuts" user "Board Geometry/Outline")
		(27 "Margin" user)
		(31 "F.CrtYd" user "Package Geometry/Place Bound Top")
		(29 "B.CrtYd" user "Package Geometry/Place Bound Bottom")
		(35 "F.Fab" user "Ref Des/Assembly Top")
		(33 "B.Fab" user "Ref Des/Assembly Bottom")
	)
	(footprint ""
		(layer "F.Cu")
		(at 1.148588 -14.695932)
		(property "Reference" "CT31"
			(at -0.81153 0.6096 90)
			(unlocked yes)
			(layer "F.SilkS")
			(effects
				(font
					(size 0.7874 0.5842)
					(thickness 0.1524)
				)
				(justify left)
			)
		)
		(property "Value" ""
			(at 0 0 0)
			(layer "F.Fab")
			(effects
				(font
					(size 1.27 1.27)
				)
			)
		)
		(duplicate_pad_numbers_are_jumpers no)
		(fp_rect
			(start -0.3048 0.9906)
			(end 0.3048 -0.1016)
			(stroke
				(width 0)
				(type default)
			)
			(fill no)
			(layer "F.CrtYd")
		)
		(fp_line
			(start -0.3048 -0.1016)
			(end -0.3048 0.9906)
			(stroke
				(width 0.1)
				(type default)
			)
			(layer "F.Fab")
		)
		(fp_line
			(start -0.3048 0.9906)
			(end 0.3048 0.9906)
			(stroke
				(width 0.1)
				(type default)
			)
			(layer "F.Fab")
		)
		(fp_line
			(start 0.3048 -0.1016)
			(end -0.3048 -0.1016)
			(stroke
				(width 0.1)
				(type default)
			)
			(layer "F.Fab")
		)
		(fp_line
			(start 0.3048 0.9906)
			(end 0.3048 -0.1016)
			(stroke
				(width 0.1)
				(type default)
			)
			(layer "F.Fab")
		)
		(pad "1" smd rect
			(at 0 0)
			(size 0.508 0.508)
			(layers "F.Cu" "F.Mask" "F.Paste")
			(net "VR_PVDDQ_GHJ_AIREF2")
		)
		(pad "2" smd rect
			(at 0 0.889)
			(size 0.508 0.508)
			(layers "F.Cu" "F.Mask" "F.Paste")
			(net "GND")
		)
		(zone
			(layer "F.Cu")
			(hatch none 0.5)
			(connect_pads
				(clearance 0)
			)
			(min_thickness 0.25)
			(keepout
				(tracks allowed)
				(vias not_allowed)
				(pads allowed)
				(copperpour not_allowed)
				(footprints allowed)
			)
			(placement
				(enabled no)
				(sheetname "")
			)
			(fill
				(thermal_gap 0.5)
				(thermal_bridge_width 0.5)
				(island_removal_mode 0)
			)
			(polygon
				(pts
					(xy 0.894588 -14.060932) (xy 1.402588 -14.060932) (xy 1.402588 -14.441932) (xy 0.894588 -14.441932)
				)
			)
		)
		(zone
			(layer "F.Cu")
			(hatch none 0.5)
			(connect_pads
				(clearance 0)
			)
			(min_thickness 0.25)
			(keepout
				(tracks not_allowed)
				(vias allowed)
				(pads allowed)
				(copperpour not_allowed)
				(footprints allowed)
			)
			(placement
				(enabled no)
				(sheetname "")
			)
			(fill
				(thermal_gap 0.5)
				(thermal_bridge_width 0.5)
				(island_removal_mode 0)
			)
			(polygon
				(pts
					(xy 0.894588 -14.060932) (xy 1.402588 -14.060932) (xy 1.402588 -14.441932) (xy 0.894588 -14.441932)
				)
			)
		)
	)
	(footprint ""
		(layer "F.Cu")
		(at 410.048964 -23.070566)
		(property "Reference" "R25W143"
			(at -0.8382 -0.67818 0)
			(unlocked yes)
			(layer "F.SilkS")
			(effects
				(font
					(size 0.4064 0.254)
					(thickness 0.1524)
				)
				(justify left)
			)
		)
		(property "Value" ""
			(at 0 0 0)
			(layer "F.Fab")
			(effects
				(font
					(size 1.27 1.27)
				)
			)
		)
		(duplicate_pad_numbers_are_jumpers no)
		(fp_poly
			(pts
				(xy -0.2794 -0.1016) (xy 0.2794 -0.1016) (xy 0.2794 0.9906) (xy -0.2794 0.9906)
			)
			(stroke
				(width 0)
				(type default)
			)
			(fill no)
			(layer "F.CrtYd")
		)
		(fp_line
			(start -0.2794 -0.1016)
			(end -0.2794 0.9906)
			(stroke
				(width 0.1)
				(type default)
			)
			(layer "F.Fab")
		)
		(fp_line
			(start -0.2794 0.9906)
			(end 0.2794 0.9906)
			(stroke
				(width 0.1)
				(type default)
			)
			(layer "F.Fab")
		)
		(fp_line
			(start 0.2794 -0.1016)
			(end -0.2794 -0.1016)
			(stroke
				(width 0.1)
				(type default)
			)
			(layer "F.Fab")
		)
		(fp_line
			(start 0.2794 0.9906)
			(end 0.2794 -0.1016)
			(stroke
				(width 0.1)
				(type default)
			)
			(layer "F.Fab")
		)
		(pad "1" smd rect
			(at 0 0)
			(size 0.508 0.508)
			(layers "F.Cu" "F.Mask" "F.Paste")
			(net "FM_GLOBAL_RST_WARN_N_R")
		)
		(pad "2" smd rect
			(at 0 0.889)
			(size 0.508 0.508)
			(layers "F.Cu" "F.Mask" "F.Paste")
			(net "FM_GLOBAL_RST_WARN_N")
		)
		(zone
			(layer "F.Cu")
			(hatch none 0.5)
			(connect_pads
				(clearance 0)
			)
			(min_thickness 0.25)
			(keepout
				(tracks allowed)
				(vias not_allowed)
				(pads allowed)
				(copperpour not_allowed)
				(footprints allowed)
			)
			(placement
				(enabled no)
				(sheetname "")
			)
			(fill
				(thermal_gap 0.5)
				(thermal_bridge_width 0.5)
				(island_removal_mode 0)
			)
			(polygon
				(pts
					(xy 409.794964 -22.816566) (xy 410.302964 -22.816566) (xy 410.302964 -22.435566) (xy 409.794964 -22.435566)
				)
			)
		)
		(zone
			(layer "F.Cu")
			(hatch none 0.5)
			(connect_pads
				(clearance 0)
			)
			(min_thickness 0.25)
			(keepout
				(tracks not_allowed)
				(vias allowed)
				(pads allowed)
				(copperpour not_allowed)
				(footprints allowed)
			)
			(placement
				(enabled no)
				(sheetname "")
			)
			(fill
				(thermal_gap 0.5)
				(thermal_bridge_width 0.5)
				(island_removal_mode 0)
			)
			(polygon
				(pts
					(xy 409.794964 -22.435566) (xy 410.302964 -22.435566) (xy 410.302964 -22.816566) (xy 409.794964 -22.816566)
				)
			)
		)
	)
	(footprint ""
		(layer "F.Cu")
		(at 19.177 10.7315 -90)
		(property "Reference" "T1P27"
			(at 0 0 270)
			(layer "F.SilkS")
			(hide yes)
			(effects
				(font
					(size 1.27 1.27)
				)
			)
		)
		(property "Value" "*"
			(at 0 -3.44805 270)
			(unlocked yes)
			(layer "F.Fab")
			(hide yes)
			(effects
				(font
					(size 0.889 0.889)
					(thickness 0.1524)
				)
			)
		)
		(property "Device Type" "TPAD-SE-2P-GP_DISCRET-GA1-TPADA"
			(at 0 -4.97205 270)
			(unlocked yes)
			(layer "F.Fab")
			(hide yes)
			(effects
				(font
					(size 0.889 0.889)
					(thickness 0.1524)
				)
			)
		)
		(duplicate_pad_numbers_are_jumpers no)
		(fp_line
			(start -1.016 2.286)
			(end -1.016 -2.286)
			(stroke
				(width 0.1524)
				(type default)
			)
			(layer "F.SilkS")
		)
		(fp_line
			(start 1.016 2.286)
			(end -1.016 2.286)
			(stroke
				(width 0.1524)
				(type default)
			)
			(layer "F.SilkS")
		)
		(fp_line
			(start -1.016 -2.286)
			(end 1.016 -2.286)
			(stroke
				(width 0.1524)
				(type default)
			)
			(layer "F.SilkS")
		)
		(fp_line
			(start 1.016 -2.286)
			(end 1.016 2.286)
			(stroke
				(width 0.1524)
				(type default)
			)
			(layer "F.SilkS")
		)
		(fp_rect
			(start -1.27 2.54)
			(end 1.27 -2.54)
			(stroke
				(width 0)
				(type default)
			)
			(fill no)
			(layer "F.CrtYd")
		)
		(fp_rect
			(start -1.27 2.54)
			(end 1.27 -2.54)
			(stroke
				(width 0)
				(type default)
			)
			(fill no)
			(layer "F.Fab")
		)
		(pad "1" thru_hole circle
			(at 0 -1.27 270)
			(size 1.524 1.524)
			(drill 0.9144)
			(layers "*.Cu" "*.Mask")
			(remove_unused_layers no)
			(net "L5_40OHM_6INCH")
			(clearance -0.0508)
			(thermal_gap 0.127)
			(padstack
				(mode front_inner_back)
				(layer "Inner"
					(shape circle)
					(size 1.1684 1.1684)
					(clearance 0.127)
				)
				(layer "B.Cu"
					(shape circle)
					(size 1.524 1.524)
					(clearance -0.0508)
				)
			)
		)
		(pad "GND1" thru_hole rect
			(at 0 1.27 270)
			(size 1.524 1.524)
			(drill 0.9144)
			(layers "*.Cu" "*.Mask")
			(remove_unused_layers no)
			(net "GND")
			(clearance -0.0508)
			(thermal_gap 0.127)
			(padstack
				(mode front_inner_back)
				(layer "Inner"
					(shape circle)
					(size 1.1684 1.1684)
					(clearance 0.127)
				)
				(layer "B.Cu"
					(shape rect)
					(size 1.524 1.524)
					(clearance -0.0508)
				)
			)
		)
	)
)
